FILE_TYPE = MACRO_DRAWING;
SET COLOR_WIRE YELLOW;
SET COLOR_PROP ORANGE;
SET COLOR_DOT WHITE;
SET COLOR_ARC YELLOW;
SET COLOR_BODY GREEN;
SET COLOR_NOTE PURPLE;
SET PROP_DISPLAY VALUE;
SET PAGE_NUMBER P47;
FORCEADD OFFPAGE..2
R 2
(-3400 4225);
FORCEPROP 2 LAST $XR0 284 
J 0
(-3685 4225);
DISPLAY 0.638298 (-3685 4225);
PAINT MONO (-3685 4225);
FORCEPROP 2 LAST CDS_LIB standard
J 0
(-3400 4225);
PAINT MONO (-3400 4225);
DISPLAY INVISIBLE (-3400 4225);
FORCEPROP 1 LAST OFFPAGE TRUE
J 2
(-3725 4100);
DISPLAY 0.872340 (-3725 4100);
DISPLAY INVISIBLE (-3725 4100);
FORCEPROP 1 LAST COMMENT_BODY TRUE
J 2
(-3355 4130);
DISPLAY 0.872340 (-3355 4130);
PAINT GREEN (-3355 4130);
DISPLAY INVISIBLE (-3355 4130);
FORCEPROP 2 LAST PATH I1
J 0
(-3350 4300);
DISPLAY 1.021277 (-3350 4300);
DISPLAY INVISIBLE (-3350 4300);
FORCEADD OFFPAGE..2
R 2
(-3400 4925);
FORCEPROP 2 LAST $XR0 292 
J 0
(-3685 4925);
DISPLAY 0.638298 (-3685 4925);
PAINT MONO (-3685 4925);
FORCEPROP 2 LAST CDS_LIB standard
J 0
(-3400 4925);
PAINT MONO (-3400 4925);
DISPLAY INVISIBLE (-3400 4925);
FORCEPROP 1 LAST OFFPAGE TRUE
J 2
(-3725 4800);
DISPLAY 0.872340 (-3725 4800);
DISPLAY INVISIBLE (-3725 4800);
FORCEPROP 1 LAST COMMENT_BODY TRUE
J 2
(-3355 4830);
DISPLAY 0.872340 (-3355 4830);
PAINT GREEN (-3355 4830);
DISPLAY INVISIBLE (-3355 4830);
FORCEPROP 2 LAST PATH I10
J 0
(-3350 5000);
DISPLAY 1.021277 (-3350 5000);
DISPLAY INVISIBLE (-3350 5000);
FORCEADD OFFPAGE..2
R 2
(-3400 4975);
FORCEPROP 2 LAST $XR0 292 
J 0
(-3685 4975);
DISPLAY 0.638298 (-3685 4975);
PAINT MONO (-3685 4975);
FORCEPROP 2 LAST CDS_LIB standard
J 0
(-3400 4975);
PAINT MONO (-3400 4975);
DISPLAY INVISIBLE (-3400 4975);
FORCEPROP 1 LAST OFFPAGE TRUE
J 2
(-3725 4850);
DISPLAY 0.872340 (-3725 4850);
DISPLAY INVISIBLE (-3725 4850);
FORCEPROP 1 LAST COMMENT_BODY TRUE
J 2
(-3355 4880);
DISPLAY 0.872340 (-3355 4880);
PAINT GREEN (-3355 4880);
DISPLAY INVISIBLE (-3355 4880);
FORCEPROP 2 LAST PATH I11
J 0
(-3350 5050);
DISPLAY 1.021277 (-3350 5050);
DISPLAY INVISIBLE (-3350 5050);
FORCEADD SOCKET4677_AZIF0045P001C01CS..4
(-450 4875);
FORCEPROP 1 LAST PART_NUMBER DGA^7000023
J 0
(-1550 5825);
DISPLAY 0.723404 (-1550 5825);
PAINT GREEN (-1550 5825);
DISPLAY INVISIBLE (-1550 5825);
FORCEPROP 2 LAST PART_TYPE SMLF
J 0
(-1550 6000);
DISPLAY 1.021277 (-1550 6000);
FORCEPROP 1 LAST MATERIAL IO
J 0
(-1550 5750);
DISPLAY 0.723404 (-1550 5750);
PAINT GREEN (-1550 5750);
FORCEPROP 2 LAST VALUE SOCKET4677_AZIF0045-P001C01CS
J 0
(-1550 5950);
DISPLAY 1.021277 (-1550 5950);
FORCEPROP 1 LAST $LOCATION U1
J 0
(-1550 5900);
DISPLAY 0.723404 (-1550 5900);
PAINT GREEN (-1550 5900);
FORCEPROP 0 LASTPIN (775 4625) $PN BL23
J 0
(785 4635);
DISPLAY 0.680851 (785 4635);
PAINT MONO (785 4635);
FORCEPROP 0 LASTPIN (775 4575) $PN BN25
J 0
(785 4585);
DISPLAY 0.680851 (785 4585);
PAINT MONO (785 4585);
FORCEPROP 0 LASTPIN (775 4525) $PN BJ23
J 0
(785 4535);
DISPLAY 0.680851 (785 4535);
PAINT MONO (785 4535);
FORCEPROP 0 LASTPIN (775 4475) $PN BK24
J 0
(785 4485);
DISPLAY 0.680851 (785 4485);
PAINT MONO (785 4485);
FORCEPROP 0 LASTPIN (-1675 4525) $PN BD24
J 2
(-1685 4535);
DISPLAY 0.680851 (-1685 4535);
PAINT MONO (-1685 4535);
FORCEPROP 0 LASTPIN (775 5075) $PN BH22
J 0
(785 5085);
DISPLAY 0.680851 (785 5085);
PAINT MONO (785 5085);
FORCEPROP 0 LASTPIN (-1675 4375) $PN BU11
J 2
(-1685 4385);
DISPLAY 0.680851 (-1685 4385);
PAINT MONO (-1685 4385);
FORCEPROP 0 LASTPIN (-1675 4225) $PN AY85
J 2
(-1685 4235);
DISPLAY 0.680851 (-1685 4235);
PAINT MONO (-1685 4235);
FORCEPROP 0 LASTPIN (-1675 4975) $PN AU11
J 2
(-1685 4985);
DISPLAY 0.680851 (-1685 4985);
PAINT MONO (-1685 4985);
FORCEPROP 0 LASTPIN (-1675 4825) $PN BD87
J 2
(-1685 4835);
DISPLAY 0.680851 (-1685 4835);
PAINT MONO (-1685 4835);
FORCEPROP 0 LASTPIN (-1675 4675) $PN CA11
J 2
(-1685 4685);
DISPLAY 0.680851 (-1685 4685);
PAINT MONO (-1685 4685);
FORCEPROP 0 LASTPIN (-1675 4325) $PN BN11
J 2
(-1685 4335);
DISPLAY 0.680851 (-1685 4335);
PAINT MONO (-1685 4335);
FORCEPROP 0 LASTPIN (-1675 4175) $PN AT85
J 2
(-1685 4185);
DISPLAY 0.680851 (-1685 4185);
PAINT MONO (-1685 4185);
FORCEPROP 0 LASTPIN (-1675 4925) $PN BA11
J 2
(-1685 4935);
DISPLAY 0.680851 (-1685 4935);
PAINT MONO (-1685 4935);
FORCEPROP 0 LASTPIN (-1675 4775) $PN BC90
J 2
(-1685 4785);
DISPLAY 0.680851 (-1685 4785);
PAINT MONO (-1685 4785);
FORCEPROP 0 LASTPIN (-1675 4625) $PN CE11
J 2
(-1685 4635);
DISPLAY 0.680851 (-1685 4635);
PAINT MONO (-1685 4635);
FORCEPROP 0 LASTPIN (-1675 5375) $PN AU33
J 2
(-1685 5385);
DISPLAY 0.680851 (-1685 5385);
PAINT MONO (-1685 5385);
FORCEPROP 0 LASTPIN (-1675 5525) $PN AU56
J 2
(-1685 5535);
DISPLAY 0.680851 (-1685 5535);
PAINT MONO (-1685 5535);
FORCEPROP 0 LASTPIN (-1675 5575) $PN AU58
J 2
(-1685 5585);
DISPLAY 0.680851 (-1685 5585);
PAINT MONO (-1685 5585);
FORCEPROP 0 LASTPIN (-1675 5425) $PN AV32
J 2
(-1685 5435);
DISPLAY 0.680851 (-1685 5435);
PAINT MONO (-1685 5435);
FORCEPROP 0 LASTPIN (775 5525) $PN AV38
J 0
(785 5535);
DISPLAY 0.680851 (785 5535);
PAINT MONO (785 5535);
FORCEPROP 0 LASTPIN (775 5575) $PN AV40
J 0
(785 5585);
DISPLAY 0.680851 (785 5585);
PAINT MONO (785 5585);
FORCEPROP 0 LASTPIN (775 5275) $PN BC23
J 0
(785 5285);
DISPLAY 0.680851 (785 5285);
PAINT MONO (785 5285);
FORCEPROP 0 LASTPIN (775 5175) $PN BE23
J 0
(785 5185);
DISPLAY 0.680851 (785 5185);
PAINT MONO (785 5185);
FORCEPROP 0 LASTPIN (775 5225) $PN BF24
J 0
(785 5235);
DISPLAY 0.680851 (785 5235);
PAINT MONO (785 5235);
FORCEPROP 0 LASTPIN (775 4775) $PN CC64
J 0
(785 4785);
DISPLAY 0.680851 (785 4785);
PAINT MONO (785 4785);
FORCEPROP 0 LASTPIN (775 4825) $PN CE62
J 0
(785 4835);
DISPLAY 0.680851 (785 4835);
PAINT MONO (785 4835);
FORCEPROP 0 LASTPIN (775 4925) $PN CN60
J 0
(785 4935);
DISPLAY 0.680851 (785 4935);
PAINT MONO (785 4935);
FORCEPROP 0 LASTPIN (775 4725) $PN CP61
J 0
(785 4735);
DISPLAY 0.680851 (785 4735);
PAINT MONO (785 4735);
FORCEPROP 0 LASTPIN (775 4975) $PN CR60
J 0
(785 4985);
DISPLAY 0.680851 (785 4985);
PAINT MONO (785 4985);
FORCEPROP 0 LASTPIN (775 4875) $PN CU62
J 0
(785 4885);
DISPLAY 0.680851 (785 4885);
PAINT MONO (785 4885);
FORCEPROP 0 LASTPIN (-1675 5275) $PN CY24
J 2
(-1685 5285);
DISPLAY 0.680851 (-1685 5285);
PAINT MONO (-1685 5285);
FORCEPROP 0 LASTPIN (-1675 5225) $PN CY38
J 2
(-1685 5235);
DISPLAY 0.680851 (-1685 5235);
PAINT MONO (-1685 5235);
FORCEPROP 0 LASTPIN (-1675 5075) $PN CY49
J 2
(-1685 5085);
DISPLAY 0.680851 (-1685 5085);
PAINT MONO (-1685 5085);
FORCEPROP 0 LASTPIN (-1675 5125) $PN DA45
J 2
(-1685 5135);
DISPLAY 0.680851 (-1685 5135);
PAINT MONO (-1685 5135);
FORCEPROP 0 LASTPIN (775 5425) $PN H12
J 0
(785 5435);
DISPLAY 0.680851 (785 5435);
PAINT MONO (785 5435);
FORCEPROP 2 LAST CDS_LIB pure_quanta
J 0
(-450 4875);
DISPLAY INVISIBLE (-450 4875);
FORCEPROP 1 LAST NEEDS_NO_SIZE TRUE
J 0
(-450 4875);
DISPLAY 0.723404 (-450 4875);
PAINT GREEN (-450 4875);
DISPLAY INVISIBLE (-450 4875);
FORCEPROP 1 LAST CDS_LMAN_SYM_OUTLINE -1100,850,1050,-850
J 0
(-450 4875);
DISPLAY 0.468085 (-450 4875);
PAINT GREEN (-450 4875);
DISPLAY INVISIBLE (-450 4875);
FORCEPROP 2 LAST CDS_LOCATION U1
J 0
(-1550 6050);
DISPLAY 1.021277 (-1550 6050);
DISPLAY INVISIBLE (-1550 6050);
FORCEPROP 0 LAST $SEC 4
J 0
(-1550 6050);
DISPLAY 0.680851 (-1550 6050);
PAINT MONO (-1550 6050);
DISPLAY INVISIBLE (-1550 6050);
FORCEPROP 2 LAST CDS_SEC 4
J 0
(-1550 6050);
DISPLAY 1.021277 (-1550 6050);
DISPLAY INVISIBLE (-1550 6050);
FORCEPROP 1 LAST PATH I16
J 0
(-450 4875);
DISPLAY 0.723404 (-450 4875);
PAINT GREEN (-450 4875);
DISPLAY INVISIBLE (-450 4875);
FORCEADD OFFPAGE..2
R 2
(-3400 4175);
FORCEPROP 2 LAST $XR0 284 
J 0
(-3685 4175);
DISPLAY 0.638298 (-3685 4175);
PAINT MONO (-3685 4175);
FORCEPROP 2 LAST CDS_LIB standard
J 0
(-3400 4175);
PAINT MONO (-3400 4175);
DISPLAY INVISIBLE (-3400 4175);
FORCEPROP 1 LAST OFFPAGE TRUE
J 2
(-3725 4050);
DISPLAY 0.872340 (-3725 4050);
DISPLAY INVISIBLE (-3725 4050);
FORCEPROP 1 LAST COMMENT_BODY TRUE
J 2
(-3355 4080);
DISPLAY 0.872340 (-3355 4080);
PAINT GREEN (-3355 4080);
DISPLAY INVISIBLE (-3355 4080);
FORCEPROP 2 LAST PATH I2
J 0
(-3350 4250);
DISPLAY 1.021277 (-3350 4250);
DISPLAY INVISIBLE (-3350 4250);
FORCEADD Q_RES..1
(2250 4475);
FORCEPROP 1 LAST PART_NUMBER CS01002FB07
J 0
(2375 4500);
DISPLAY 0.404255 (2375 4500);
DISPLAY INVISIBLE (2375 4500);
FORCEPROP 1 LAST WATTAGE 1/16W
J 2
(2700 4500);
DISPLAY 0.404255 (2700 4500);
FORCEPROP 1 LAST PACK_TYPE 0402LF
J 0
(2575 4475);
DISPLAY 0.510638 (2575 4475);
FORCEPROP 1 LAST MATERIAL CHIP
J 0
(2725 4500);
DISPLAY 0.404255 (2725 4500);
FORCEPROP 1 LAST VALUE 10
J 2
(2425 4475);
DISPLAY 0.510638 (2425 4475);
FORCEPROP 1 LAST TOLERANCE 1%
J 0
(2475 4475);
DISPLAY 0.510638 (2475 4475);
FORCEPROP 1 LAST $LOCATION R54
J 0
(2075 4475);
DISPLAY 0.808511 (2075 4475);
FORCEPROP 1 LASTPIN (2150 4475) $PN 1
J 0
(2162 4487);
DISPLAY 0.787234 (2162 4487);
FORCEPROP 1 LASTPIN (2350 4475) $PN 2
J 0
(2312 4487);
DISPLAY 0.787234 (2312 4487);
FORCEPROP 2 LAST CDS_LIB pure_quanta
J 0
(2250 4475);
PAINT MONO (2250 4475);
DISPLAY INVISIBLE (2250 4475);
FORCEPROP 1 LAST $LOCATION R54
J 0
(2200 4675);
DISPLAY 1.021277 (2200 4675);
DISPLAY INVISIBLE (2200 4675);
FORCEPROP 2 LAST CDS_LOCATION R54
J 0
(2200 4675);
DISPLAY 1.021277 (2200 4675);
DISPLAY INVISIBLE (2200 4675);
FORCEPROP 2 LAST $SEC 1
J 0
(2200 4675);
DISPLAY 0.680851 (2200 4675);
PAINT MONO (2200 4675);
DISPLAY INVISIBLE (2200 4675);
FORCEPROP 2 LAST CDS_SEC 1
J 0
(2200 4675);
DISPLAY 1.021277 (2200 4675);
DISPLAY INVISIBLE (2200 4675);
FORCEPROP 1 LAST PATH I22
J 0
(2200 4625);
DISPLAY 0.978723 (2200 4625);
PAINT WHITE (2200 4625);
DISPLAY INVISIBLE (2200 4625);
FORCEADD Q_RES..1
(2250 4525);
FORCEPROP 1 LAST PART_NUMBER CS01002FB07
J 0
(2375 4550);
DISPLAY 0.404255 (2375 4550);
DISPLAY INVISIBLE (2375 4550);
FORCEPROP 1 LAST WATTAGE 1/16W
J 2
(2700 4550);
DISPLAY 0.404255 (2700 4550);
FORCEPROP 1 LAST PACK_TYPE 0402LF
J 0
(2575 4525);
DISPLAY 0.510638 (2575 4525);
FORCEPROP 1 LAST VALUE 10
J 2
(2425 4525);
DISPLAY 0.510638 (2425 4525);
FORCEPROP 1 LAST TOLERANCE 1%
J 0
(2475 4525);
DISPLAY 0.510638 (2475 4525);
FORCEPROP 1 LAST MATERIAL CHIP
J 0
(2725 4550);
DISPLAY 0.404255 (2725 4550);
FORCEPROP 1 LAST $LOCATION R53
J 0
(2075 4525);
DISPLAY 0.808511 (2075 4525);
FORCEPROP 1 LASTPIN (2150 4525) $PN 1
J 0
(2162 4537);
DISPLAY 0.787234 (2162 4537);
FORCEPROP 1 LASTPIN (2350 4525) $PN 2
J 0
(2312 4537);
DISPLAY 0.787234 (2312 4537);
FORCEPROP 2 LAST CDS_LIB pure_quanta
J 0
(2250 4525);
PAINT MONO (2250 4525);
DISPLAY INVISIBLE (2250 4525);
FORCEPROP 1 LAST $LOCATION R53
J 0
(2200 4725);
DISPLAY 1.021277 (2200 4725);
DISPLAY INVISIBLE (2200 4725);
FORCEPROP 2 LAST CDS_LOCATION R53
J 0
(2200 4725);
DISPLAY 1.021277 (2200 4725);
DISPLAY INVISIBLE (2200 4725);
FORCEPROP 2 LAST $SEC 1
J 0
(2200 4725);
DISPLAY 0.680851 (2200 4725);
PAINT MONO (2200 4725);
DISPLAY INVISIBLE (2200 4725);
FORCEPROP 2 LAST CDS_SEC 1
J 0
(2200 4725);
DISPLAY 1.021277 (2200 4725);
DISPLAY INVISIBLE (2200 4725);
FORCEPROP 1 LAST PATH I23
J 0
(2200 4675);
DISPLAY 0.978723 (2200 4675);
PAINT WHITE (2200 4675);
DISPLAY INVISIBLE (2200 4675);
FORCEADD Q_RES..1
(2250 4625);
FORCEPROP 1 LAST PART_NUMBER CS11002FB07
J 0
(2375 4600);
DISPLAY 0.404255 (2375 4600);
DISPLAY INVISIBLE (2375 4600);
FORCEPROP 1 LAST WATTAGE 1/16W
J 2
(2700 4600);
DISPLAY 0.404255 (2700 4600);
FORCEPROP 1 LAST PACK_TYPE 0402LF
J 0
(2575 4625);
DISPLAY 0.510638 (2575 4625);
FORCEPROP 1 LAST TOLERANCE 1%
J 0
(2475 4625);
DISPLAY 0.510638 (2475 4625);
FORCEPROP 1 LAST VALUE 100
J 2
(2450 4625);
DISPLAY 0.510638 (2450 4625);
FORCEPROP 1 LAST MATERIAL CHIP
J 0
(2725 4600);
DISPLAY 0.404255 (2725 4600);
FORCEPROP 1 LAST $LOCATION R51
J 0
(2075 4625);
DISPLAY 0.787234 (2075 4625);
FORCEPROP 1 LASTPIN (2150 4625) $PN 1
J 0
(2162 4637);
DISPLAY 0.787234 (2162 4637);
FORCEPROP 1 LASTPIN (2350 4625) $PN 2
J 0
(2312 4637);
DISPLAY 0.787234 (2312 4637);
FORCEPROP 2 LAST CDS_LIB pure_quanta
J 0
(2250 4625);
PAINT MONO (2250 4625);
DISPLAY INVISIBLE (2250 4625);
FORCEPROP 1 LAST $LOCATION R51
J 0
(2200 4825);
DISPLAY 1.021277 (2200 4825);
DISPLAY INVISIBLE (2200 4825);
FORCEPROP 2 LAST CDS_LOCATION R51
J 0
(2200 4825);
DISPLAY 1.021277 (2200 4825);
DISPLAY INVISIBLE (2200 4825);
FORCEPROP 2 LAST $SEC 1
J 0
(2200 4825);
DISPLAY 0.680851 (2200 4825);
PAINT MONO (2200 4825);
DISPLAY INVISIBLE (2200 4825);
FORCEPROP 2 LAST CDS_SEC 1
J 0
(2200 4825);
DISPLAY 1.021277 (2200 4825);
DISPLAY INVISIBLE (2200 4825);
FORCEPROP 1 LAST PATH I24
J 0
(2200 4775);
DISPLAY 0.978723 (2200 4775);
PAINT WHITE (2200 4775);
DISPLAY INVISIBLE (2200 4775);
FORCEADD Q_RES..1
(2250 4575);
FORCEPROP 1 LAST PART_NUMBER CS11002FB07
J 0
(2375 4550);
DISPLAY 0.404255 (2375 4550);
DISPLAY INVISIBLE (2375 4550);
FORCEPROP 1 LAST WATTAGE 1/16W
J 2
(2700 4550);
DISPLAY 0.404255 (2700 4550);
FORCEPROP 1 LAST PACK_TYPE 0402LF
J 0
(2575 4575);
DISPLAY 0.510638 (2575 4575);
FORCEPROP 1 LAST VALUE 100
J 2
(2450 4575);
DISPLAY 0.510638 (2450 4575);
FORCEPROP 1 LAST TOLERANCE 1%
J 0
(2475 4575);
DISPLAY 0.510638 (2475 4575);
FORCEPROP 1 LAST MATERIAL CHIP
J 0
(2725 4550);
DISPLAY 0.404255 (2725 4550);
FORCEPROP 1 LAST $LOCATION R52
J 0
(2075 4575);
DISPLAY 0.787234 (2075 4575);
FORCEPROP 1 LASTPIN (2150 4575) $PN 1
J 0
(2162 4587);
DISPLAY 0.787234 (2162 4587);
FORCEPROP 1 LASTPIN (2350 4575) $PN 2
J 0
(2312 4587);
DISPLAY 0.787234 (2312 4587);
FORCEPROP 2 LAST CDS_LIB pure_quanta
J 0
(2250 4575);
PAINT MONO (2250 4575);
DISPLAY INVISIBLE (2250 4575);
FORCEPROP 1 LAST $LOCATION R52
J 0
(2200 4775);
DISPLAY 1.021277 (2200 4775);
DISPLAY INVISIBLE (2200 4775);
FORCEPROP 2 LAST CDS_LOCATION R52
J 0
(2200 4775);
DISPLAY 1.021277 (2200 4775);
DISPLAY INVISIBLE (2200 4775);
FORCEPROP 2 LAST $SEC 1
J 0
(2200 4775);
DISPLAY 0.680851 (2200 4775);
PAINT MONO (2200 4775);
DISPLAY INVISIBLE (2200 4775);
FORCEPROP 2 LAST CDS_SEC 1
J 0
(2200 4775);
DISPLAY 1.021277 (2200 4775);
DISPLAY INVISIBLE (2200 4775);
FORCEPROP 1 LAST PATH I25
J 0
(2200 4725);
DISPLAY 0.978723 (2200 4725);
PAINT WHITE (2200 4725);
DISPLAY INVISIBLE (2200 4725);
FORCEADD OFFPAGE..3
(2500 5075);
FORCEPROP 2 LAST $XR0 118 
J 0
(2714 5075);
DISPLAY 0.638298 (2714 5075);
PAINT MONO (2714 5075);
FORCEPROP 2 LAST CDS_LIB standard
J 0
(2500 5075);
PAINT MONO (2500 5075);
DISPLAY INVISIBLE (2500 5075);
FORCEPROP 1 LAST OFFPAGE TRUE
J 0
(2825 4950);
DISPLAY 1.170213 (2825 4950);
PAINT GREEN (2825 4950);
DISPLAY INVISIBLE (2825 4950);
FORCEPROP 1 LAST COMMENT_BODY TRUE
J 0
(2450 4975);
DISPLAY 1.170213 (2450 4975);
PAINT GREEN (2450 4975);
DISPLAY INVISIBLE (2450 4975);
FORCEPROP 2 LAST PATH I26
J 0
(2700 5150);
DISPLAY 1.021277 (2700 5150);
DISPLAY INVISIBLE (2700 5150);
FORCEADD OFFPAGE..2
R 2
(-3400 4325);
FORCEPROP 2 LAST $XR0 296 
J 0
(-3685 4325);
DISPLAY 0.638298 (-3685 4325);
PAINT MONO (-3685 4325);
FORCEPROP 2 LAST CDS_LIB standard
J 0
(-3400 4325);
PAINT MONO (-3400 4325);
DISPLAY INVISIBLE (-3400 4325);
FORCEPROP 1 LAST OFFPAGE TRUE
J 2
(-3725 4200);
DISPLAY 0.872340 (-3725 4200);
DISPLAY INVISIBLE (-3725 4200);
FORCEPROP 1 LAST COMMENT_BODY TRUE
J 2
(-3355 4230);
DISPLAY 0.872340 (-3355 4230);
PAINT GREEN (-3355 4230);
DISPLAY INVISIBLE (-3355 4230);
FORCEPROP 2 LAST PATH I3
J 0
(-3350 4400);
DISPLAY 1.021277 (-3350 4400);
DISPLAY INVISIBLE (-3350 4400);
FORCEADD OFFPAGE..3
(4050 4475);
FORCEPROP 2 LAST $XR1 132 
J 0
(4354 4475);
DISPLAY 0.638298 (4354 4475);
PAINT MONO (4354 4475);
FORCEPROP 2 LAST $XR0 16 
J 0
(4264 4475);
DISPLAY 0.638298 (4264 4475);
PAINT MONO (4264 4475);
FORCEPROP 2 LAST CDS_LIB standard
J 0
(4050 4475);
PAINT MONO (4050 4475);
DISPLAY INVISIBLE (4050 4475);
FORCEPROP 1 LAST OFFPAGE TRUE
J 0
(4375 4350);
DISPLAY 1.170213 (4375 4350);
PAINT GREEN (4375 4350);
DISPLAY INVISIBLE (4375 4350);
FORCEPROP 1 LAST COMMENT_BODY TRUE
J 0
(4000 4375);
DISPLAY 1.170213 (4000 4375);
PAINT GREEN (4000 4375);
DISPLAY INVISIBLE (4000 4375);
FORCEPROP 2 LAST PATH I30
J 0
(4250 4550);
DISPLAY 1.021277 (4250 4550);
DISPLAY INVISIBLE (4250 4550);
FORCEADD OFFPAGE..3
(4050 4525);
FORCEPROP 2 LAST $XR1 132 
J 0
(4354 4525);
DISPLAY 0.638298 (4354 4525);
PAINT MONO (4354 4525);
FORCEPROP 2 LAST $XR0 16 
J 0
(4264 4525);
DISPLAY 0.638298 (4264 4525);
PAINT MONO (4264 4525);
FORCEPROP 2 LAST CDS_LIB standard
J 0
(4050 4525);
PAINT MONO (4050 4525);
DISPLAY INVISIBLE (4050 4525);
FORCEPROP 1 LAST OFFPAGE TRUE
J 0
(4375 4400);
DISPLAY 1.170213 (4375 4400);
PAINT GREEN (4375 4400);
DISPLAY INVISIBLE (4375 4400);
FORCEPROP 1 LAST COMMENT_BODY TRUE
J 0
(4000 4425);
DISPLAY 1.170213 (4000 4425);
PAINT GREEN (4000 4425);
DISPLAY INVISIBLE (4000 4425);
FORCEPROP 2 LAST PATH I31
J 0
(4250 4600);
DISPLAY 1.021277 (4250 4600);
DISPLAY INVISIBLE (4250 4600);
FORCEADD OFFPAGE..3
(4050 4575);
FORCEPROP 2 LAST $XR0 16 
J 0
(4264 4575);
DISPLAY 0.638298 (4264 4575);
PAINT MONO (4264 4575);
FORCEPROP 2 LAST CDS_LIB standard
J 0
(4050 4575);
PAINT MONO (4050 4575);
DISPLAY INVISIBLE (4050 4575);
FORCEPROP 1 LAST OFFPAGE TRUE
J 0
(4375 4450);
DISPLAY 1.170213 (4375 4450);
PAINT GREEN (4375 4450);
DISPLAY INVISIBLE (4375 4450);
FORCEPROP 1 LAST COMMENT_BODY TRUE
J 0
(4000 4475);
DISPLAY 1.170213 (4000 4475);
PAINT GREEN (4000 4475);
DISPLAY INVISIBLE (4000 4475);
FORCEPROP 2 LAST PATH I32
J 0
(4250 4650);
DISPLAY 1.021277 (4250 4650);
DISPLAY INVISIBLE (4250 4650);
FORCEADD OFFPAGE..3
(4050 4625);
FORCEPROP 2 LAST $XR0 16 
J 0
(4264 4625);
DISPLAY 0.638298 (4264 4625);
PAINT MONO (4264 4625);
FORCEPROP 2 LAST CDS_LIB standard
J 0
(4050 4625);
PAINT MONO (4050 4625);
DISPLAY INVISIBLE (4050 4625);
FORCEPROP 1 LAST OFFPAGE TRUE
J 0
(4375 4500);
DISPLAY 1.170213 (4375 4500);
PAINT GREEN (4375 4500);
DISPLAY INVISIBLE (4375 4500);
FORCEPROP 1 LAST COMMENT_BODY TRUE
J 0
(4000 4525);
DISPLAY 1.170213 (4000 4525);
PAINT GREEN (4000 4525);
DISPLAY INVISIBLE (4000 4525);
FORCEPROP 2 LAST PATH I33
J 0
(4250 4700);
DISPLAY 1.021277 (4250 4700);
DISPLAY INVISIBLE (4250 4700);
FORCEADD Q_RES..2
(3675 4975);
FORCEPROP 1 LAST PART_NUMBER CS14992FB06
J 0
(3715 4850);
DISPLAY 0.638298 (3715 4850);
DISPLAY INVISIBLE (3715 4850);
FORCEPROP 1 LAST WATTAGE 1/16W
J 0
(3715 4950);
DISPLAY 0.638298 (3715 4950);
FORCEPROP 1 LAST PACK_TYPE 0402LF
J 0
(3715 4850);
DISPLAY 0.638298 (3715 4850);
FORCEPROP 1 LAST TOLERANCE 1%
J 0
(3720 5000);
DISPLAY 0.638298 (3720 5000);
FORCEPROP 1 LAST VALUE 499
J 0
(3720 5050);
DISPLAY 0.638298 (3720 5050);
FORCEPROP 1 LAST MATERIAL CHIP
J 0
(3715 4900);
DISPLAY 0.638298 (3715 4900);
FORCEPROP 1 LAST $LOCATION R49
J 0
(3720 5100);
DISPLAY 0.978723 (3720 5100);
FORCEPROP 1 LASTPIN (3675 5075) $PN 1
J 0
(3680 5037);
DISPLAY 0.787234 (3680 5037);
FORCEPROP 1 LASTPIN (3675 4875) $PN 2
J 0
(3680 4885);
DISPLAY 0.787234 (3680 4885);
FORCEPROP 2 LAST CDS_LIB pure_quanta
J 0
(3675 4975);
PAINT MONO (3675 4975);
DISPLAY INVISIBLE (3675 4975);
FORCEPROP 1 LAST $LOCATION R49
J 0
(3725 5200);
DISPLAY 1.021277 (3725 5200);
DISPLAY INVISIBLE (3725 5200);
FORCEPROP 2 LAST CDS_LOCATION R49
J 0
(3725 5200);
DISPLAY 1.021277 (3725 5200);
DISPLAY INVISIBLE (3725 5200);
FORCEPROP 2 LAST $SEC 1
J 0
(3725 5200);
DISPLAY 0.680851 (3725 5200);
PAINT MONO (3725 5200);
DISPLAY INVISIBLE (3725 5200);
FORCEPROP 2 LAST CDS_SEC 1
J 0
(3725 5200);
DISPLAY 1.021277 (3725 5200);
DISPLAY INVISIBLE (3725 5200);
FORCEPROP 1 LAST PATH I34
J 0
(3725 5150);
DISPLAY 0.978723 (3725 5150);
PAINT WHITE (3725 5150);
DISPLAY INVISIBLE (3725 5150);
FORCEADD Q_RES..2
(3925 4975);
FORCEPROP 1 LAST PART_NUMBER CS14992FB06
J 0
(3965 4800);
DISPLAY 0.638298 (3965 4800);
DISPLAY INVISIBLE (3965 4800);
FORCEPROP 1 LAST MATERIAL CHIP
J 0
(3965 4900);
DISPLAY 0.638298 (3965 4900);
FORCEPROP 1 LAST TOLERANCE 1%
J 0
(3970 5000);
DISPLAY 0.638298 (3970 5000);
FORCEPROP 1 LAST PACK_TYPE 0402LF
J 0
(3965 4850);
DISPLAY 0.638298 (3965 4850);
FORCEPROP 1 LAST WATTAGE 1/16W
J 0
(3965 4950);
DISPLAY 0.638298 (3965 4950);
FORCEPROP 1 LAST VALUE 499
J 0
(3970 5050);
DISPLAY 0.638298 (3970 5050);
FORCEPROP 1 LAST $LOCATION R50
J 0
(3970 5100);
DISPLAY 0.978723 (3970 5100);
FORCEPROP 1 LASTPIN (3925 5075) $PN 1
J 0
(3930 5037);
DISPLAY 0.787234 (3930 5037);
FORCEPROP 1 LASTPIN (3925 4875) $PN 2
J 0
(3930 4885);
DISPLAY 0.787234 (3930 4885);
FORCEPROP 2 LAST CDS_LIB pure_quanta
J 0
(3925 4975);
PAINT MONO (3925 4975);
DISPLAY INVISIBLE (3925 4975);
FORCEPROP 1 LAST $LOCATION R50
J 0
(3975 5200);
DISPLAY 1.021277 (3975 5200);
DISPLAY INVISIBLE (3975 5200);
FORCEPROP 2 LAST CDS_LOCATION R50
J 0
(3975 5200);
DISPLAY 1.021277 (3975 5200);
DISPLAY INVISIBLE (3975 5200);
FORCEPROP 2 LAST $SEC 1
J 0
(3975 5200);
DISPLAY 0.680851 (3975 5200);
PAINT MONO (3975 5200);
DISPLAY INVISIBLE (3975 5200);
FORCEPROP 2 LAST CDS_SEC 1
J 0
(3975 5200);
DISPLAY 1.021277 (3975 5200);
DISPLAY INVISIBLE (3975 5200);
FORCEPROP 1 LAST PATH I35
J 0
(3975 5150);
DISPLAY 0.978723 (3975 5150);
PAINT WHITE (3975 5150);
DISPLAY INVISIBLE (3975 5150);
FORCEADD UNIVERSAL_POWER..1
(3675 5300);
FORCEPROP 3 LASTPIN (3675 5250) SIG_NAME PVNN_TERM_CPU1\g
J 0
(3685 5260);
DISPLAY 0.659574 (3685 5260);
PAINT MONO (3685 5260);
DISPLAY INVISIBLE (3685 5260);
FORCEPROP 1 LAST HDL_POWER PVNN_TERM_CPU1
J 1
(3675 5350);
DISPLAY 0.872340 (3675 5350);
PAINT GREEN (3675 5350);
FORCEPROP 2 LAST CDS_LIB logical_power
J 0
(3675 5300);
PAINT MONO (3675 5300);
DISPLAY INVISIBLE (3675 5300);
FORCEPROP 1 LAST PATH I36
J 0
(3725 5325);
DISPLAY 0.872340 (3725 5325);
PAINT AQUA (3725 5325);
DISPLAY INVISIBLE (3725 5325);
FORCEADD OFFPAGE..1
(-3400 4525);
FORCEPROP 2 LAST $XR0 117 
J 0
(-3652 4525);
DISPLAY 0.638298 (-3652 4525);
PAINT MONO (-3652 4525);
FORCEPROP 2 LAST CDS_LIB standard
J 0
(-3400 4525);
PAINT MONO (-3400 4525);
DISPLAY INVISIBLE (-3400 4525);
FORCEPROP 1 LAST OFFPAGE TRUE
J 0
(-3075 4400);
DISPLAY 0.872340 (-3075 4400);
DISPLAY INVISIBLE (-3075 4400);
FORCEPROP 1 LAST COMMENT_BODY TRUE
J 0
(-3275 4425);
DISPLAY 0.872340 (-3275 4425);
PAINT GREEN (-3275 4425);
DISPLAY INVISIBLE (-3275 4425);
FORCEPROP 2 LAST PATH I4
J 0
(-3350 4600);
DISPLAY 1.021277 (-3350 4600);
DISPLAY INVISIBLE (-3350 4600);
FORCEADD OFFPAGE..2
R 2
(-3400 4375);
FORCEPROP 2 LAST $XR0 296 
J 0
(-3685 4375);
DISPLAY 0.638298 (-3685 4375);
PAINT MONO (-3685 4375);
FORCEPROP 2 LAST CDS_LIB standard
J 0
(-3400 4375);
PAINT MONO (-3400 4375);
DISPLAY INVISIBLE (-3400 4375);
FORCEPROP 1 LAST OFFPAGE TRUE
J 2
(-3725 4250);
DISPLAY 0.872340 (-3725 4250);
DISPLAY INVISIBLE (-3725 4250);
FORCEPROP 1 LAST COMMENT_BODY TRUE
J 2
(-3355 4280);
DISPLAY 0.872340 (-3355 4280);
PAINT GREEN (-3355 4280);
DISPLAY INVISIBLE (-3355 4280);
FORCEPROP 2 LAST PATH I5
J 0
(-3350 4450);
DISPLAY 1.021277 (-3350 4450);
DISPLAY INVISIBLE (-3350 4450);
FORCEADD OFFPAGE..2
R 2
(-3400 4625);
FORCEPROP 2 LAST $XR0 292 
J 0
(-3685 4625);
DISPLAY 0.638298 (-3685 4625);
PAINT MONO (-3685 4625);
FORCEPROP 2 LAST CDS_LIB standard
J 0
(-3400 4625);
PAINT MONO (-3400 4625);
DISPLAY INVISIBLE (-3400 4625);
FORCEPROP 1 LAST OFFPAGE TRUE
J 2
(-3725 4500);
DISPLAY 0.872340 (-3725 4500);
DISPLAY INVISIBLE (-3725 4500);
FORCEPROP 1 LAST COMMENT_BODY TRUE
J 2
(-3355 4530);
DISPLAY 0.872340 (-3355 4530);
PAINT GREEN (-3355 4530);
DISPLAY INVISIBLE (-3355 4530);
FORCEPROP 2 LAST PATH I6
J 0
(-3350 4700);
DISPLAY 1.021277 (-3350 4700);
DISPLAY INVISIBLE (-3350 4700);
FORCEADD OFFPAGE..2
R 2
(-3400 4675);
FORCEPROP 2 LAST $XR0 292 
J 0
(-3685 4675);
DISPLAY 0.638298 (-3685 4675);
PAINT MONO (-3685 4675);
FORCEPROP 2 LAST CDS_LIB standard
J 0
(-3400 4675);
PAINT MONO (-3400 4675);
DISPLAY INVISIBLE (-3400 4675);
FORCEPROP 1 LAST OFFPAGE TRUE
J 2
(-3725 4550);
DISPLAY 0.872340 (-3725 4550);
DISPLAY INVISIBLE (-3725 4550);
FORCEPROP 1 LAST COMMENT_BODY TRUE
J 2
(-3355 4580);
DISPLAY 0.872340 (-3355 4580);
PAINT GREEN (-3355 4580);
DISPLAY INVISIBLE (-3355 4580);
FORCEPROP 2 LAST PATH I7
J 0
(-3350 4750);
DISPLAY 1.021277 (-3350 4750);
DISPLAY INVISIBLE (-3350 4750);
FORCEADD OFFPAGE..2
R 2
(-3400 4775);
FORCEPROP 2 LAST $XR0 284 
J 0
(-3685 4775);
DISPLAY 0.638298 (-3685 4775);
PAINT MONO (-3685 4775);
FORCEPROP 2 LAST CDS_LIB standard
J 0
(-3400 4775);
PAINT MONO (-3400 4775);
DISPLAY INVISIBLE (-3400 4775);
FORCEPROP 1 LAST OFFPAGE TRUE
J 2
(-3725 4650);
DISPLAY 0.872340 (-3725 4650);
DISPLAY INVISIBLE (-3725 4650);
FORCEPROP 1 LAST COMMENT_BODY TRUE
J 2
(-3355 4680);
DISPLAY 0.872340 (-3355 4680);
PAINT GREEN (-3355 4680);
DISPLAY INVISIBLE (-3355 4680);
FORCEPROP 2 LAST PATH I8
J 0
(-3350 4850);
DISPLAY 1.021277 (-3350 4850);
DISPLAY INVISIBLE (-3350 4850);
FORCEADD OFFPAGE..2
R 2
(-3400 4825);
FORCEPROP 2 LAST $XR0 284 
J 0
(-3685 4825);
DISPLAY 0.638298 (-3685 4825);
PAINT MONO (-3685 4825);
FORCEPROP 2 LAST CDS_LIB standard
J 0
(-3400 4825);
PAINT MONO (-3400 4825);
DISPLAY INVISIBLE (-3400 4825);
FORCEPROP 1 LAST OFFPAGE TRUE
J 2
(-3725 4700);
DISPLAY 0.872340 (-3725 4700);
DISPLAY INVISIBLE (-3725 4700);
FORCEPROP 1 LAST COMMENT_BODY TRUE
J 2
(-3355 4730);
DISPLAY 0.872340 (-3355 4730);
PAINT GREEN (-3355 4730);
DISPLAY INVISIBLE (-3355 4730);
FORCEPROP 2 LAST PATH I9
J 0
(-3350 4900);
DISPLAY 1.021277 (-3350 4900);
DISPLAY INVISIBLE (-3350 4900);
FORCEADD QUANTA_TITLE_BLOCK_C..1
(5250 350);
FORCEPROP 0 LAST CDS_CON_LAST_MODIFIED Fri Aug 25 14:00:30 2023
J 0
(3365 365);
PAINT MONO (3365 365);
DISPLAY INVISIBLE (3365 365);
FORCEPROP 2 LAST CUSTOM_TXT_CDS <XR_PAGE_TITLE>
J 0
(-2640 5600);
DISPLAY 0.638298 (-2640 5600);
PAINT PINK (-2640 5600);
DISPLAY INVISIBLE (-2640 5600);
FORCEPROP 2 LAST CUSTOM_TXT_CDS <Q_PROJ>
J 0
(2868 452);
DISPLAY 1.212766 (2868 452);
FORCEPROP 2 LAST CUSTOM_TXT_CDS <CON_LAST_MODIFIED>
J 0
(3365 365);
DISPLAY 0.978723 (3365 365);
FORCEPROP 2 LAST CUSTOM_TXT_CDS <CON_PAGE_NUM> OF <CON_TOTAL_PAGES>
J 0
(4804 368);
DISPLAY 0.978723 (4804 368);
FORCEPROP 2 LAST CUSTOM_TXT_CDS <Q_REV>
J 0
(5066 453);
DISPLAY 1.212766 (5066 453);
FORCEPROP 2 LAST CUSTOM_TXT_CDS <Q_NUMBER>
J 0
(3847 453);
DISPLAY 1.212766 (3847 453);
FORCEPROP 1 LAST CUSTOM_TXT_CDS <NAME_2>
J 0
(2075 400);
FORCEPROP 1 LAST CUSTOM_TXT_CDS <NAME_1>
J 0
(2075 525);
FORCEPROP 1 LAST Q_TITLE SPR CPU1 MISC:DDRVIEW & VSENSE(4/30)
J 0
(-4116 376);
DISPLAY 1.957447 (-4116 376);
PAINT GREEN (-4116 376);
FORCEPROP 1 LAST Q_DEPT 
J 1
(1487 399);
DISPLAY 1.957447 (1487 399);
PAINT GREEN (1487 399);
FORCEPROP 2 LAST PAGE_BORDER TRUE
J 0
(-2640 5600);
DISPLAY 0.638298 (-2640 5600);
PAINT PINK (-2640 5600);
DISPLAY INVISIBLE (-2640 5600);
FORCEPROP 1 LAST CDS_LMAN_SYM_OUTLINE -9475,6775,100,-125
J 0
(5250 350);
DISPLAY 0.468085 (5250 350);
PAINT GREEN (5250 350);
DISPLAY INVISIBLE (5250 350);
FORCEPROP 2 LAST CDS_LIB pure_quanta
J 0
(5250 350);
PAINT MONO (5250 350);
DISPLAY INVISIBLE (5250 350);
FORCEPROP 2 LAST CDS_XR_PAGE_TITLE CR-47 : @S9S_MB_2U_LIB.S9S_MB_2U(SCH_1):PAGE47
J 0
(-2640 5600);
DISPLAY 0.638298 (-2640 5600);
PAINT PINK (-2640 5600);
DISPLAY INVISIBLE (-2640 5600);
FORCEPROP 1 LAST COMMENT_BODY TRUE
J 0
(5262 337);
DISPLAY 0.978723 (5262 337);
PAINT GREEN (5262 337);
DISPLAY INVISIBLE (5262 337);
WIRE 16 -1 (3675 5250)(3675 5200);
WIRE 16 -1 (-1675 5225)(-3350 5225);
FORCEPROP 0 LAST CDS_PHYS_NET_NAME VSENSE_PVCCFA_EHV_CPU1_DP
J 0
(-3287 5266);
PAINT MONO (-3287 5266);
DISPLAY INVISIBLE (-3287 5266);
FORCEPROP 2 LAST SIG_NAME NC_CPU1_DDR45_VIEWDIG1
J 0
(-3287 5234);
DISPLAY 0.680851 (-3287 5234);
PAINT WHITE (-3287 5234);
WIRE 16 -1 (-1675 5125)(-3350 5125);
FORCEPROP 2 LAST SIG_NAME NC_CPU1_DDR67_VIEWDIG0
J 0
(-3287 5134);
DISPLAY 0.680851 (-3287 5134);
PAINT WHITE (-3287 5134);
WIRE 16 -1 (-1675 5075)(-3350 5075);
FORCEPROP 0 LAST CDS_PHYS_NET_NAME VSENSE_PVCCFA_EHV_CPU1_DP
J 0
(-3287 5116);
PAINT MONO (-3287 5116);
DISPLAY INVISIBLE (-3287 5116);
FORCEPROP 2 LAST SIG_NAME NC_CPU1_DDR67_VIEWDIG1
J 0
(-3287 5084);
DISPLAY 0.680851 (-3287 5084);
PAINT WHITE (-3287 5084);
WIRE 16 -1 (-1675 4525)(-3350 4525);
FORCEPROP 2 LAST SIG_NAME H_PMAX_TRIGGER_IO_CPU1
J 0
(-3287 4534);
DISPLAY 0.680851 (-3287 4534);
PAINT WHITE (-3287 4534);
WIRE 16 -1 (-1675 5575)(-3350 5575);
FORCEPROP 2 LAST SIG_NAME NC_CPU1_DDR01_VIEWDIG0
J 0
(-3287 5584);
DISPLAY 0.680851 (-3287 5584);
PAINT WHITE (-3287 5584);
WIRE 16 -1 (-1675 5275)(-3350 5275);
FORCEPROP 2 LAST SIG_NAME NC_CPU1_DDR45_VIEWDIG0
J 0
(-3287 5284);
DISPLAY 0.680851 (-3287 5284);
PAINT WHITE (-3287 5284);
WIRE 16 -1 (-1675 5425)(-3350 5425);
FORCEPROP 2 LAST SIG_NAME NC_CPU1_DDR23_VIEWDIG0
J 0
(-3287 5434);
DISPLAY 0.680851 (-3287 5434);
PAINT WHITE (-3287 5434);
WIRE 16 -1 (-1675 5375)(-3350 5375);
FORCEPROP 0 LAST CDS_PHYS_NET_NAME VSENSE_PVCCFA_EHV_CPU1_DP
J 0
(-3287 5416);
PAINT MONO (-3287 5416);
DISPLAY INVISIBLE (-3287 5416);
FORCEPROP 2 LAST SIG_NAME NC_CPU1_DDR23_VIEWDIG1
J 0
(-3287 5384);
DISPLAY 0.680851 (-3287 5384);
PAINT WHITE (-3287 5384);
WIRE 16 -1 (-1675 5525)(-3350 5525);
FORCEPROP 0 LAST CDS_PHYS_NET_NAME VSENSE_PVCCFA_EHV_CPU1_DP
J 0
(-3287 5566);
PAINT MONO (-3287 5566);
DISPLAY INVISIBLE (-3287 5566);
FORCEPROP 2 LAST SIG_NAME NC_CPU1_DDR01_VIEWDIG1
J 0
(-3287 5534);
DISPLAY 0.680851 (-3287 5534);
PAINT WHITE (-3287 5534);
WIRE 16 -1 (-1675 4375)(-3350 4375);
FORCEPROP 2 LAST SIG_NAME VSENSE_PVCCD_HV_CPU1_DP
J 0
(-3287 4384);
DISPLAY 0.680851 (-3287 4384);
PAINT WHITE (-3287 4384);
WIRE 16 -1 (-1675 4225)(-3350 4225);
FORCEPROP 2 LAST SIG_NAME VSENSE_PVCCFA_EHV_FIVRA_CPU1_DP
J 0
(-3287 4234);
DISPLAY 0.680851 (-3287 4234);
PAINT WHITE (-3287 4234);
WIRE 16 -1 (-1675 4975)(-3350 4975);
FORCEPROP 2 LAST SIG_NAME VSENSE_PVCCFA_EHV_CPU1_DP
J 0
(-3287 4984);
DISPLAY 0.680851 (-3287 4984);
PAINT WHITE (-3287 4984);
WIRE 16 -1 (-1675 4675)(-3350 4675);
FORCEPROP 2 LAST SIG_NAME VSENSE_PVCCINFAON_CPU1_DP
J 0
(-3287 4684);
DISPLAY 0.680851 (-3287 4684);
PAINT WHITE (-3287 4684);
WIRE 16 -1 (-1675 4825)(-3350 4825);
FORCEPROP 2 LAST SIG_NAME VSENSE_PVCCIN_CPU1_DP
J 0
(-3287 4834);
DISPLAY 0.680851 (-3287 4834);
PAINT WHITE (-3287 4834);
WIRE 16 -1 (-1675 4325)(-3350 4325);
FORCEPROP 2 LAST SIG_NAME VSENSE_PVCCD_HV_CPU1_DN
J 0
(-3287 4334);
DISPLAY 0.680851 (-3287 4334);
PAINT WHITE (-3287 4334);
WIRE 16 -1 (-1675 4175)(-3350 4175);
FORCEPROP 2 LAST SIG_NAME VSENSE_PVCCFA_EHV_FIVRA_CPU1_DN
J 0
(-3287 4184);
DISPLAY 0.680851 (-3287 4184);
PAINT WHITE (-3287 4184);
WIRE 16 -1 (-1675 4925)(-3350 4925);
FORCEPROP 2 LAST SIG_NAME VSENSE_PVCCFA_EHV_CPU1_DN
J 0
(-3287 4934);
DISPLAY 0.680851 (-3287 4934);
PAINT WHITE (-3287 4934);
WIRE 16 -1 (-1675 4625)(-3350 4625);
FORCEPROP 2 LAST SIG_NAME VSENSE_PVCCINFAON_CPU1_DN
J 0
(-3287 4634);
DISPLAY 0.680851 (-3287 4634);
PAINT WHITE (-3287 4634);
WIRE 16 -1 (-1675 4775)(-3350 4775);
FORCEPROP 2 LAST SIG_NAME VSENSE_PVCCIN_CPU1_DN
J 0
(-3287 4784);
DISPLAY 0.680851 (-3287 4784);
PAINT WHITE (-3287 4784);
WIRE 16 -1 (2450 4775)(775 4775);
FORCEPROP 2 LAST SIG_NAME NC_CPU1_LGSSPARE4
J 0
(1009 4784);
DISPLAY 0.680851 (1009 4784);
PAINT WHITE (1009 4784);
WIRE 16 -1 (2450 5575)(775 5575);
FORCEPROP 2 LAST SIG_NAME NC_CPU1_THERMADA
J 0
(1009 5584);
DISPLAY 0.680851 (1009 5584);
PAINT WHITE (1009 5584);
WIRE 16 -1 (2450 5525)(775 5525);
FORCEPROP 2 LAST SIG_NAME NC_CPU1_THERMADC
J 0
(1009 5534);
DISPLAY 0.680851 (1009 5534);
PAINT WHITE (1009 5534);
WIRE 16 -1 (2450 5425)(775 5425);
FORCEPROP 2 LAST SIG_NAME TP_CPU1_A0_DEBUG_EN
J 0
(1009 5434);
DISPLAY 0.680851 (1009 5434);
PAINT WHITE (1009 5434);
WIRE 16 -1 (2450 4975)(775 4975);
FORCEPROP 2 LAST SIG_NAME NC_CPU1_LGSSPARE0
J 0
(1009 4984);
DISPLAY 0.680851 (1009 4984);
PAINT WHITE (1009 4984);
WIRE 16 -1 (2450 4725)(775 4725);
FORCEPROP 2 LAST SIG_NAME NC_CPU1_LGSSPARE5
J 0
(1009 4734);
DISPLAY 0.680851 (1009 4734);
PAINT WHITE (1009 4734);
WIRE 16 -1 (2450 4925)(775 4925);
FORCEPROP 2 LAST SIG_NAME NC_CPU1_LGSSPARE1
J 0
(1009 4934);
DISPLAY 0.680851 (1009 4934);
PAINT WHITE (1009 4934);
WIRE 16 -1 (2450 4875)(775 4875);
FORCEPROP 2 LAST SIG_NAME NC_CPU1_LGSSPARE2
J 0
(1009 4884);
DISPLAY 0.680851 (1009 4884);
PAINT WHITE (1009 4884);
WIRE 16 -1 (2450 4825)(775 4825);
FORCEPROP 2 LAST SIG_NAME NC_CPU1_LGSSPARE3
J 0
(1009 4834);
DISPLAY 0.680851 (1009 4834);
PAINT WHITE (1009 4834);
WIRE 16 -1 (2450 5075)(775 5075);
FORCEPROP 2 LAST SIG_NAME H_CPU1_RMCA_LVC1_R_N
J 0
(1009 5084);
DISPLAY 0.680851 (1009 5084);
PAINT WHITE (1009 5084);
WIRE 16 -1 (2150 4475)(775 4475);
FORCEPROP 2 LAST SIG_NAME DBP_CPU1_HOOK9_MBP3_GTL_QS_R_N
J 0
(1009 4484);
DISPLAY 0.680851 (1009 4484);
PAINT WHITE (1009 4484);
WIRE 16 -1 (2150 4525)(775 4525);
FORCEPROP 2 LAST SIG_NAME DBP_CPU1_HOOK8_MBP2_GTL_QS_R_N
J 0
(1009 4534);
DISPLAY 0.680851 (1009 4534);
PAINT WHITE (1009 4534);
WIRE 16 -1 (2150 4575)(775 4575);
FORCEPROP 2 LAST SIG_NAME DBP_CPU1_MBP1_GTL_R_N
J 0
(1009 4584);
DISPLAY 0.680851 (1009 4584);
PAINT WHITE (1009 4584);
WIRE 16 -1 (2150 4625)(775 4625);
FORCEPROP 2 LAST SIG_NAME DBP_CPU1_MBP0_GTL_R_N
J 0
(1009 4634);
DISPLAY 0.680851 (1009 4634);
PAINT WHITE (1009 4634);
WIRE 16 -1 (2450 5225)(775 5225);
FORCEPROP 2 LAST SIG_NAME TP_CPU1_IFST_TRIG_LVC1_R
J 0
(1009 5234);
DISPLAY 0.680851 (1009 5234);
PAINT WHITE (1009 5234);
WIRE 16 -1 (2450 5175)(775 5175);
FORCEPROP 2 LAST SIG_NAME TP_CPU1_IFST_KOT_LVC1_R
J 0
(1009 5184);
DISPLAY 0.680851 (1009 5184);
PAINT WHITE (1009 5184);
WIRE 16 -1 (2450 5275)(775 5275);
FORCEPROP 2 LAST SIG_NAME TP_CPU1_IFST_DONE_LVC1_R
J 0
(1009 5284);
DISPLAY 0.680851 (1009 5284);
PAINT WHITE (1009 5284);
WIRE 16 -1 (3925 4575)(2350 4575);
FORCEPROP 2 LAST SIG_NAME DBP_CPU_MBP1_GTL_N
J 0
(2909 4584);
DISPLAY 0.680851 (2909 4584);
PAINT WHITE (2909 4584);
WIRE 16 -1 (4000 4575)(3925 4575);
WIRE 16 -1 (3925 4875)(3925 4575);
WIRE 16 -1 (3925 5200)(3925 5075);
WIRE 16 -1 (3675 5200)(3675 5075);
WIRE 16 -1 (3675 5200)(3925 5200);
WIRE 16 -1 (3675 4875)(3675 4625);
WIRE 16 -1 (4000 4625)(3675 4625);
WIRE 16 -1 (2350 4625)(3675 4625);
FORCEPROP 2 LAST SIG_NAME DBP_CPU_MBP0_GTL_N
J 0
(2909 4634);
DISPLAY 0.680851 (2909 4634);
PAINT WHITE (2909 4634);
WIRE 16 -1 (2350 4525)(4000 4525);
FORCEPROP 2 LAST SIG_NAME DBP_CPU_HOOK8_MBP2_GTL_QS_N
J 0
(2909 4534);
DISPLAY 0.680851 (2909 4534);
PAINT WHITE (2909 4534);
WIRE 16 -1 (2350 4475)(4000 4475);
FORCEPROP 2 LAST SIG_NAME DBP_CPU_HOOK9_MBP3_GTL_QS_N
J 0
(2909 4484);
DISPLAY 0.680851 (2909 4484);
PAINT WHITE (2909 4484);
DOT 1 (3675 5200);
DOT 1 (3675 4625);
DOT 1 (3925 4575);
QUIT
